(kicad_pcb
	(version 20241229)
	(generator "pcbnew")
	(generator_version "9.0")
	(general
		(thickness 1.6296)
		(legacy_teardrops no)
	)
	(paper "A3")
	(title_block
		(title "Thunderbolt to 10GbE adapter")
		(date "2026-04-21")
		(rev "1.1.0")
		(company "Antmicro Ltd")
		(comment 1 "www.antmicro.com")
		(comment 9 "footprints 210-213 of 703")
	)
	(layers
		(0 "F.Cu" signal)
		(4 "In1.Cu" signal)
		(6 "In2.Cu" signal)
		(8 "In3.Cu" signal)
		(10 "In4.Cu" signal)
		(12 "In5.Cu" signal)
		(14 "In6.Cu" signal)
		(2 "B.Cu" signal)
		(9 "F.Adhes" user "F.Adhesive")
		(11 "B.Adhes" user "B.Adhesive")
		(13 "F.Paste" user)
		(15 "B.Paste" user)
		(5 "F.SilkS" user "F.Silkscreen")
		(7 "B.SilkS" user "B.Silkscreen")
		(1 "F.Mask" user)
		(3 "B.Mask" user)
		(17 "Dwgs.User" user "User.Drawings")
		(19 "Cmts.User" user "User.Comments")
		(21 "Eco1.User" user "User.Eco1")
		(23 "Eco2.User" user "User.Eco2")
		(25 "Edge.Cuts" user)
		(27 "Margin" user)
		(31 "F.CrtYd" user "F.Courtyard")
		(29 "B.CrtYd" user "B.Courtyard")
		(35 "F.Fab" user)
		(33 "B.Fab" user)
	)
	(footprint "antmicro-footprints:C_0805_2012Metric"
		(layer "F.Cu")
		(at 119.65 109.75 180)
		(descr "Capacitor SMD 0805")
		(tags "capacitor SMD 0805")
		(property "Reference" "C8"
			(at -6.55 -5.45 180)
			(layer "F.SilkS")
			(effects
				(font
					(size 0.7 0.7)
					(thickness 0.15)
				)
			)
		)
		(property "Value" "C_22u_25V_0805"
			(at -2.055717 1.963152 180)
			(layer "F.Fab")
			(effects
				(font
					(size 0.7 0.7)
					(thickness 0.15)
				)
				(justify left bottom)
			)
		)
		(property "Datasheet" "https://product.samsungsem.com/mlcc/CL21A226MAYNNN.do"
			(at 0 0 180)
			(layer "F.Fab")
			(hide yes)
			(effects
				(font
					(size 1.27 1.27)
					(thickness 0.15)
				)
			)
		)
		(property "Description" "SMT Multilayer Ceramic Capacitor, 22uF, +/-20%, 25V, X5R, 0805 [2012 Metric]"
			(at 0 0 180)
			(layer "F.Fab")
			(hide yes)
			(effects
				(font
					(size 1.27 1.27)
					(thickness 0.15)
				)
			)
		)
		(property "MPN" "CL21A226MAYNNNE"
			(at 0 0 180)
			(unlocked yes)
			(layer "F.Fab")
			(hide yes)
			(effects
				(font
					(size 1 1)
					(thickness 0.15)
				)
			)
		)
		(property "Manufacturer" "Samsung Electro-Mechanics"
			(at 0 0 180)
			(unlocked yes)
			(layer "F.Fab")
			(hide yes)
			(effects
				(font
					(size 1 1)
					(thickness 0.15)
				)
			)
		)
		(property "License" "Apache-2.0"
			(at 0 0 180)
			(unlocked yes)
			(layer "F.Fab")
			(hide yes)
			(effects
				(font
					(size 1 1)
					(thickness 0.15)
				)
			)
		)
		(property "Author" "Antmicro"
			(at 0 0 180)
			(unlocked yes)
			(layer "F.Fab")
			(hide yes)
			(effects
				(font
					(size 1 1)
					(thickness 0.15)
				)
			)
		)
		(property "Val" "22u"
			(at 0 0 180)
			(unlocked yes)
			(layer "F.Fab")
			(hide yes)
			(effects
				(font
					(size 1 1)
					(thickness 0.15)
				)
			)
		)
		(property "Voltage" "25V"
			(at 0 0 180)
			(unlocked yes)
			(layer "F.Fab")
			(hide yes)
			(effects
				(font
					(size 1 1)
					(thickness 0.15)
				)
			)
		)
		(property "Dielectric" "X5R"
			(at 0 0 180)
			(unlocked yes)
			(layer "F.Fab")
			(hide yes)
			(effects
				(font
					(size 1 1)
					(thickness 0.15)
				)
			)
		)
		(property "Public" "False"
			(at 0 0 180)
			(unlocked yes)
			(layer "F.Fab")
			(hide yes)
			(effects
				(font
					(size 1 1)
					(thickness 0.15)
				)
			)
		)
		(sheetname "/PD and TB DC-DC/")
		(sheetfile "PD_and_TB_DC_DC.kicad_sch")
		(attr smd)
		(fp_line
			(start -0.3 0.7)
			(end 0.3 0.7)
			(stroke
				(width 0.15)
				(type solid)
			)
			(layer "F.SilkS")
		)
		(fp_line
			(start -0.3 -0.7)
			(end 0.3 -0.7)
			(stroke
				(width 0.15)
				(type solid)
			)
			(layer "F.SilkS")
		)
		(fp_rect
			(start 1.95 -0.9)
			(end -1.95 0.9)
			(stroke
				(width 0.05)
				(type default)
			)
			(fill no)
			(layer "F.CrtYd")
		)
		(fp_rect
			(start -0.95 -0.675)
			(end 0.95 0.675)
			(stroke
				(width 0.15)
				(type solid)
			)
			(fill no)
			(layer "F.Fab")
		)
		(fp_text user "${REFERENCE}"
			(at -1.9 3.947 180)
			(layer "F.Fab")
			(effects
				(font
					(size 0.7 0.7)
					(thickness 0.15)
				)
				(justify left bottom)
			)
		)
		(fp_text user "Author: Antmicro"
			(at -1.9 5.947 180)
			(layer "F.Fab")
			(effects
				(font
					(size 0.7 0.7)
					(thickness 0.15)
				)
				(justify left bottom)
			)
		)
		(fp_text user "License: Apache-2.0"
			(at -1.9 4.947 180)
			(layer "F.Fab")
			(effects
				(font
					(size 0.7 0.7)
					(thickness 0.15)
				)
				(justify left bottom)
			)
		)
		(pad "1" smd roundrect
			(at -1.1 0 180)
			(size 1.2 1.3)
			(layers "F.Cu" "F.Mask" "F.Paste")
			(roundrect_rratio 0.25)
			(net 23 "GND")
			(pintype "passive")
		)
		(pad "2" smd roundrect
			(at 1.1 0 180)
			(size 1.2 1.3)
			(layers "F.Cu" "F.Mask" "F.Paste")
			(roundrect_rratio 0.25)
			(net 161 "Net-(U2-VIN)")
			(pintype "passive")
		)
	)
	(footprint "antmicro-footprints:R_0402_1005Metric"
		(layer "F.Cu")
		(at 157.155001 67.124999 -90)
		(descr "Resistor SMD 0402")
		(tags "resistor SMD 0402")
		(property "Reference" "R158"
			(at -12.324999 -20.295 270)
			(layer "F.SilkS")
			(effects
				(font
					(size 0.7 0.7)
					(thickness 0.15)
				)
			)
		)
		(property "Value" "R_100k_0402"
			(at -1.011843 1.772047 270)
			(layer "F.Fab")
			(effects
				(font
					(size 0.7 0.7)
					(thickness 0.15)
				)
				(justify left bottom)
			)
		)
		(property "Datasheet" "https://www.bourns.com/docs/product-datasheets/cr.pdf"
			(at 0 0 270)
			(layer "F.Fab")
			(hide yes)
			(effects
				(font
					(size 1.27 1.27)
					(thickness 0.15)
				)
			)
		)
		(property "Description" "SMD Chip Resistor, 100 kohm, ± 1%, 62.5 mW, 0402 [1005 Metric], Thick Film, General Purpose"
			(at 0 0 270)
			(layer "F.Fab")
			(hide yes)
			(effects
				(font
					(size 1.27 1.27)
					(thickness 0.15)
				)
			)
		)
		(property "MPN" "CR0402-FX-1003GLF"
			(at 0 0 270)
			(unlocked yes)
			(layer "F.Fab")
			(hide yes)
			(effects
				(font
					(size 1 1)
					(thickness 0.15)
				)
			)
		)
		(property "Manufacturer" "Bourns"
			(at 0 0 270)
			(unlocked yes)
			(layer "F.Fab")
			(hide yes)
			(effects
				(font
					(size 1 1)
					(thickness 0.15)
				)
			)
		)
		(property "License" "Apache-2.0"
			(at 0 0 270)
			(unlocked yes)
			(layer "F.Fab")
			(hide yes)
			(effects
				(font
					(size 1 1)
					(thickness 0.15)
				)
			)
		)
		(property "Author" "Antmicro"
			(at 0 0 270)
			(unlocked yes)
			(layer "F.Fab")
			(hide yes)
			(effects
				(font
					(size 1 1)
					(thickness 0.15)
				)
			)
		)
		(property "Val" "100k"
			(at 0 0 270)
			(unlocked yes)
			(layer "F.Fab")
			(hide yes)
			(effects
				(font
					(size 1 1)
					(thickness 0.15)
				)
			)
		)
		(property "Tolerance" "1%"
			(at 0 0 270)
			(unlocked yes)
			(layer "F.Fab")
			(hide yes)
			(effects
				(font
					(size 1 1)
					(thickness 0.15)
				)
			)
		)
		(sheetname "/X710-AT2 Misc/")
		(sheetfile "x710-at2-mics.kicad_sch")
		(attr smd dnp)
		(fp_rect
			(start -0.925 -0.47)
			(end 0.925 0.47)
			(stroke
				(width 0.05)
				(type default)
			)
			(fill no)
			(layer "F.CrtYd")
		)
		(fp_rect
			(start -0.5 -0.25)
			(end 0.5 0.25)
			(stroke
				(width 0.15)
				(type solid)
			)
			(fill no)
			(layer "F.Fab")
		)
		(fp_text user "License: Apache-2.0"
			(at -0.95 5.169 270)
			(layer "F.Fab")
			(effects
				(font
					(size 0.7 0.7)
					(thickness 0.15)
				)
				(justify left bottom)
			)
		)
		(fp_text user "${REFERENCE}"
			(at -0.95 3.168 270)
			(layer "F.Fab")
			(effects
				(font
					(size 0.7 0.7)
					(thickness 0.15)
				)
				(justify left bottom)
			)
		)
		(fp_text user "Author: Antmicro"
			(at -0.95 4.169 270)
			(layer "F.Fab")
			(effects
				(font
					(size 0.7 0.7)
					(thickness 0.15)
				)
				(justify left bottom)
			)
		)
		(pad "1" smd roundrect
			(at -0.48 0 270)
			(size 0.59 0.64)
			(layers "F.Cu" "F.Mask" "F.Paste")
			(roundrect_rratio 0.25)
			(net 141 "/X710-AT2 Misc/NCSI.ARB_OUT")
			(pintype "passive")
		)
		(pad "2" smd roundrect
			(at 0.48 0 270)
			(size 0.59 0.64)
			(layers "F.Cu" "F.Mask" "F.Paste")
			(roundrect_rratio 0.25)
			(net 7 "+3V3")
			(pintype "passive")
		)
	)
	(footprint "antmicro-footprints:R_0402_1005Metric"
		(layer "F.Cu")
		(at 116.4 109.1 180)
		(descr "Resistor SMD 0402")
		(tags "resistor SMD 0402")
		(property "Reference" "R6"
			(at 0 8.1 180)
			(layer "F.SilkS")
			(effects
				(font
					(size 0.7 0.7)
					(thickness 0.15)
				)
			)
		)
		(property "Value" "R_10k_0402"
			(at -1.011843 1.772047 180)
			(layer "F.Fab")
			(effects
				(font
					(size 0.7 0.7)
					(thickness 0.15)
				)
				(justify left bottom)
			)
		)
		(property "Datasheet" "https://www.bourns.com/docs/product-datasheets/cr.pdf"
			(at 0 0 180)
			(layer "F.Fab")
			(hide yes)
			(effects
				(font
					(size 1.27 1.27)
					(thickness 0.15)
				)
			)
		)
		(property "Description" "SMD Chip Resistor, 10 kohm, ± 1%, 62.5 mW, 0402 [1005 Metric], Thick Film, General Purpose"
			(at 0 0 180)
			(layer "F.Fab")
			(hide yes)
			(effects
				(font
					(size 1.27 1.27)
					(thickness 0.15)
				)
			)
		)
		(property "MPN" "CR0402-FX-1002GLF"
			(at 0 0 180)
			(unlocked yes)
			(layer "F.Fab")
			(hide yes)
			(effects
				(font
					(size 1 1)
					(thickness 0.15)
				)
			)
		)
		(property "Manufacturer" "Bourns"
			(at 0 0 180)
			(unlocked yes)
			(layer "F.Fab")
			(hide yes)
			(effects
				(font
					(size 1 1)
					(thickness 0.15)
				)
			)
		)
		(property "License" "Apache-2.0"
			(at 0 0 180)
			(unlocked yes)
			(layer "F.Fab")
			(hide yes)
			(effects
				(font
					(size 1 1)
					(thickness 0.15)
				)
			)
		)
		(property "Val" "10k"
			(at 0 0 180)
			(unlocked yes)
			(layer "F.Fab")
			(hide yes)
			(effects
				(font
					(size 1 1)
					(thickness 0.15)
				)
			)
		)
		(property "Tolerance" "1%"
			(at 0 0 180)
			(unlocked yes)
			(layer "F.Fab")
			(hide yes)
			(effects
				(font
					(size 1 1)
					(thickness 0.15)
				)
			)
		)
		(property "Author" "Antmicro"
			(at 0 0 180)
			(unlocked yes)
			(layer "F.Fab")
			(hide yes)
			(effects
				(font
					(size 1 1)
					(thickness 0.15)
				)
			)
		)
		(sheetname "/PD and TB DC-DC/")
		(sheetfile "PD_and_TB_DC_DC.kicad_sch")
		(attr smd)
		(fp_rect
			(start -0.925 -0.47)
			(end 0.925 0.47)
			(stroke
				(width 0.05)
				(type default)
			)
			(fill no)
			(layer "F.CrtYd")
		)
		(fp_rect
			(start -0.5 -0.25)
			(end 0.5 0.25)
			(stroke
				(width 0.15)
				(type solid)
			)
			(fill no)
			(layer "F.Fab")
		)
		(fp_text user "${REFERENCE}"
			(at -0.95 3.168 180)
			(layer "F.Fab")
			(effects
				(font
					(size 0.7 0.7)
					(thickness 0.15)
				)
				(justify left bottom)
			)
		)
		(fp_text user "License: Apache-2.0"
			(at -0.95 5.169 180)
			(layer "F.Fab")
			(effects
				(font
					(size 0.7 0.7)
					(thickness 0.15)
				)
				(justify left bottom)
			)
		)
		(fp_text user "Author: Antmicro"
			(at -0.95 4.169 180)
			(layer "F.Fab")
			(effects
				(font
					(size 0.7 0.7)
					(thickness 0.15)
				)
				(justify left bottom)
			)
		)
		(pad "1" smd roundrect
			(at -0.48 0 180)
			(size 0.59 0.64)
			(layers "F.Cu" "F.Mask" "F.Paste")
			(roundrect_rratio 0.25)
			(net 413 "Net-(D3-C)")
			(pintype "passive")
		)
		(pad "2" smd roundrect
			(at 0.48 0 180)
			(size 0.59 0.64)
			(layers "F.Cu" "F.Mask" "F.Paste")
			(roundrect_rratio 0.25)
			(net 161 "Net-(U2-VIN)")
			(pintype "passive")
		)
	)
	(footprint "antmicro-footprints:R_0402_1005Metric"
		(layer "F.Cu")
		(at 164 80.4)
		(descr "Resistor SMD 0402")
		(tags "resistor SMD 0402")
		(property "Reference" "R204"
			(at -1 6.4 0)
			(layer "F.SilkS")
			(effects
				(font
					(size 0.7 0.7)
					(thickness 0.15)
				)
				(justify left bottom)
			)
		)
		(property "Value" "R_1k_0402"
			(at -1.011843 1.772047 0)
			(layer "F.Fab")
			(effects
				(font
					(size 0.7 0.7)
					(thickness 0.15)
				)
				(justify left bottom)
			)
		)
		(property "Datasheet" "https://www.bourns.com/docs/product-datasheets/cr.pdf"
			(at 0 0 0)
			(layer "F.Fab")
			(hide yes)
			(effects
				(font
					(size 1.27 1.27)
					(thickness 0.15)
				)
			)
		)
		(property "Description" "SMD Chip Resistor, 1 kohm, ± 1%, 63 mW, 0402 [1005 Metric], Thick Film, General Purpose"
			(at 0 0 0)
			(layer "F.Fab")
			(hide yes)
			(effects
				(font
					(size 1.27 1.27)
					(thickness 0.15)
				)
			)
		)
		(property "MPN" "CR0402-FX-1001GLF"
			(at 0 0 0)
			(unlocked yes)
			(layer "F.Fab")
			(hide yes)
			(effects
				(font
					(size 1 1)
					(thickness 0.15)
				)
			)
		)
		(property "Manufacturer" "Bourns"
			(at 0 0 0)
			(unlocked yes)
			(layer "F.Fab")
			(hide yes)
			(effects
				(font
					(size 1 1)
					(thickness 0.15)
				)
			)
		)
		(property "License" "Apache-2.0"
			(at 0 0 0)
			(unlocked yes)
			(layer "F.Fab")
			(hide yes)
			(effects
				(font
					(size 1 1)
					(thickness 0.15)
				)
			)
		)
		(property "Author" "Antmicro"
			(at 0 0 0)
			(unlocked yes)
			(layer "F.Fab")
			(hide yes)
			(effects
				(font
					(size 1 1)
					(thickness 0.15)
				)
			)
		)
		(property "Val" "1k"
			(at 0 0 0)
			(unlocked yes)
			(layer "F.Fab")
			(hide yes)
			(effects
				(font
					(size 1 1)
					(thickness 0.15)
				)
			)
		)
		(property "Tolerance" "1%"
			(at 0 0 0)
			(unlocked yes)
			(layer "F.Fab")
			(hide yes)
			(effects
				(font
					(size 1 1)
					(thickness 0.15)
				)
			)
		)
		(sheetname "/X710-AT2 10GbE/")
		(sheetfile "x710-at2-10gbe.kicad_sch")
		(attr smd dnp)
		(fp_rect
			(start -0.925 -0.47)
			(end 0.925 0.47)
			(stroke
				(width 0.05)
				(type default)
			)
			(fill no)
			(layer "F.CrtYd")
		)
		(fp_rect
			(start -0.5 -0.25)
			(end 0.5 0.25)
			(stroke
				(width 0.15)
				(type solid)
			)
			(fill no)
			(layer "F.Fab")
		)
		(fp_text user "Author: Antmicro"
			(at -0.95 4.169 0)
			(layer "F.Fab")
			(effects
				(font
					(size 0.7 0.7)
					(thickness 0.15)
				)
				(justify left bottom)
			)
		)
		(fp_text user "License: Apache-2.0"
			(at -0.95 5.169 0)
			(layer "F.Fab")
			(effects
				(font
					(size 0.7 0.7)
					(thickness 0.15)
				)
				(justify left bottom)
			)
		)
		(fp_text user "${REFERENCE}"
			(at -0.95 3.168 0)
			(layer "F.Fab")
			(effects
				(font
					(size 0.7 0.7)
					(thickness 0.15)
				)
				(justify left bottom)
			)
		)
		(pad "1" smd roundrect
			(at -0.48 0)
			(size 0.59 0.64)
			(layers "F.Cu" "F.Mask" "F.Paste")
			(roundrect_rratio 0.25)
			(net 130 "/X710-AT2 10GbE/TPIN_3")
			(pintype "passive")
		)
		(pad "2" smd roundrect
			(at 0.48 0)
			(size 0.59 0.64)
			(layers "F.Cu" "F.Mask" "F.Paste")
			(roundrect_rratio 0.25)
			(net 18 "+1V88")
			(pintype "passive")
		)
	)
)
